(kicad_pcb
	(version 20260206)
	(generator "pcbnew")
	(generator_version "10.0")
	(general
		(thickness 1.6)
		(legacy_teardrops no)
	)
	(paper "A4")
	(title_block
		(title "panther-plus-userver — 13130-1b_20150205.brd")
		(comment 1 "Honey Badger (Wiwynn) / footprint 1214 of 1509 (DIMM3), pads 9-15 of 210")
	)
	(layers
		(0 "F.Cu" signal "TOP")
		(4 "In1.Cu" signal "L2")
		(6 "In2.Cu" signal "L3")
		(8 "In3.Cu" signal "L4")
		(10 "In4.Cu" signal "L5")
		(12 "In5.Cu" signal "L6")
		(14 "In6.Cu" signal "L7")
		(16 "In7.Cu" signal "L8")
		(18 "In8.Cu" signal "L9")
		(20 "In9.Cu" signal "L10")
		(22 "In10.Cu" signal "L11")
		(2 "B.Cu" signal "BOTTOM")
		(9 "F.Adhes" user "F.Adhesive")
		(11 "B.Adhes" user "B.Adhesive")
		(13 "F.Paste" user "Package Geometry/Pastemask Top")
		(15 "B.Paste" user "Package Geometry/Pastemask Bottom")
		(5 "F.SilkS" user "Ref Des/Silkscreen Top")
		(7 "B.SilkS" user "Ref Des/Silkscreen Bottom")
		(1 "F.Mask" user "Board Geometry/Soldermask Top")
		(3 "B.Mask" user "Board Geometry/Soldermask Bottom")
		(17 "Dwgs.User" user "User.Drawings")
		(19 "Cmts.User" user "User.Comments")
		(21 "Eco1.User" user "User.Eco1")
		(23 "Eco2.User" user "User.Eco2")
		(25 "Edge.Cuts" user "Board Geometry/Outline")
		(27 "Margin" user)
		(31 "F.CrtYd" user "Package Geometry/Place Bound Top")
		(29 "B.CrtYd" user "Package Geometry/Place Bound Bottom")
		(35 "F.Fab" user "Ref Des/Assembly Top")
		(33 "B.Fab" user "Ref Des/Assembly Bottom")
	)
	(footprint ""
		(layer "B.Cu")
		(at 159.999934 -5.790692)
		(property "Reference" "DIMM3"
			(at 0 0 0)
			(layer "B.SilkS")
			(hide yes)
			(effects
				(font
					(size 1.27 1.27)
				)
				(justify mirror)
			)
		)
		(property "Value" "DDR3-204P-142-COLAY-1-GP-U"
			(at 41.312338 -16.676878 0)
			(unlocked yes)
			(layer "B.Fab")
			(hide yes)
			(effects
				(font
					(size 1.016 1.016)
					(thickness 0.1524)
				)
				(justify mirror)
			)
		)
		(property "Device Type" "AS0A626-J8R6-7H-COLAY-1"
			(at 41.312338 -18.200878 0)
			(unlocked yes)
			(layer "B.Fab")
			(hide yes)
			(effects
				(font
					(size 1.016 1.016)
					(thickness 0.1524)
				)
				(justify mirror)
			)
		)
		(duplicate_pad_numbers_are_jumpers no)
		(pad "7" smd custom
			(at -29.85008 -4.100068 180)
			(size 0.1143 0.1143)
			(layers "B.Cu" "B.Mask" "B.Paste")
			(net "M_B_DQ1")
			(options
				(clearance outline)
				(anchor circle)
			)
			(primitives
				(gr_poly
					(pts
						(xy 0 -0.9017) (xy -0.03175 -0.89916) (xy -0.0635 -0.889) (xy -0.09144 -0.87376) (xy -0.11684 -0.85344)
						(xy -0.13716 -0.82804) (xy -0.1524 -0.8001) (xy -0.16256 -0.76835) (xy -0.1651 -0.7366) (xy -0.1651 -0.19685)
						(xy -0.17272 -0.18923) (xy -0.17907 -0.18034) (xy -0.18669 -0.17145) (xy -0.19177 -0.16256) (xy -0.19812 -0.15367)
						(xy -0.20828 -0.13335) (xy -0.21971 -0.10287) (xy -0.22225 -0.09271) (xy -0.22479 -0.08128) (xy -0.22606 -0.07112)
						(xy -0.2286 -0.05969) (xy -0.2286 -0.01651) (xy -0.22606 -0.00508) (xy -0.22479 0.00508) (xy -0.22225 0.01651)
						(xy -0.21971 0.02667) (xy -0.20828 0.05715) (xy -0.19812 0.07747) (xy -0.19177 0.08636) (xy -0.18669 0.09525)
						(xy -0.17907 0.10414) (xy -0.17272 0.11303) (xy -0.1651 0.12065) (xy -0.1651 0.7366) (xy -0.16256 0.76835)
						(xy -0.1524 0.8001) (xy -0.13716 0.82804) (xy -0.11684 0.85344) (xy -0.09144 0.87376) (xy -0.0635 0.889)
						(xy -0.03175 0.89916) (xy 0 0.9017) (xy 0.03175 0.89916) (xy 0.0635 0.889) (xy 0.09144 0.87376)
						(xy 0.11684 0.85344) (xy 0.13716 0.82804) (xy 0.1524 0.8001) (xy 0.16256 0.76835) (xy 0.1651 0.7366)
						(xy 0.1651 0.11938) (xy 0.17272 0.11176) (xy 0.19812 0.0762) (xy 0.2032 0.06604) (xy 0.20701 0.05715)
						(xy 0.21209 0.04699) (xy 0.2159 0.03683) (xy 0.21844 0.02667) (xy 0.22225 0.01524) (xy 0.22352 0.00508)
						(xy 0.22606 -0.00508) (xy 0.22733 -0.01651) (xy 0.22733 -0.02667) (xy 0.2286 -0.0381) (xy 0.22733 -0.04953)
						(xy 0.22733 -0.05969) (xy 0.22606 -0.07112) (xy 0.22352 -0.08128) (xy 0.22225 -0.09144) (xy 0.21844 -0.10287)
						(xy 0.2159 -0.11303) (xy 0.21209 -0.12319) (xy 0.20701 -0.13335) (xy 0.2032 -0.14224) (xy 0.19812 -0.1524)
						(xy 0.17272 -0.18796) (xy 0.1651 -0.19558) (xy 0.1651 -0.7366) (xy 0.16256 -0.76835) (xy 0.1524 -0.8001)
						(xy 0.13716 -0.82804) (xy 0.11684 -0.85344) (xy 0.09144 -0.87376) (xy 0.0635 -0.889) (xy 0.03175 -0.89916)
					)
					(width 0)
					(fill yes)
				)
			)
		)
		(pad "8" smd custom
			(at -29.550106 4.100068 180)
			(size 0.1143 0.1143)
			(layers "B.Cu" "B.Mask" "B.Paste")
			(net "GND")
			(options
				(clearance outline)
				(anchor circle)
			)
			(primitives
				(gr_poly
					(pts
						(xy 0 -0.9017) (xy -0.03175 -0.89916) (xy -0.0635 -0.889) (xy -0.09144 -0.87376) (xy -0.11684 -0.85344)
						(xy -0.13716 -0.82804) (xy -0.1524 -0.8001) (xy -0.16256 -0.76835) (xy -0.1651 -0.7366) (xy -0.1651 -0.11938)
						(xy -0.17272 -0.11176) (xy -0.19812 -0.0762) (xy -0.2032 -0.06604) (xy -0.20701 -0.05715) (xy -0.21209 -0.04699)
						(xy -0.2159 -0.03683) (xy -0.21844 -0.02667) (xy -0.22225 -0.01524) (xy -0.22352 -0.00508) (xy -0.22606 0.00508)
						(xy -0.22733 0.01651) (xy -0.22733 0.02667) (xy -0.2286 0.0381) (xy -0.22733 0.04953) (xy -0.22733 0.05969)
						(xy -0.22606 0.07112) (xy -0.22352 0.08128) (xy -0.22225 0.09144) (xy -0.21844 0.10287) (xy -0.2159 0.11303)
						(xy -0.21209 0.12319) (xy -0.20701 0.13335) (xy -0.2032 0.14224) (xy -0.19812 0.1524) (xy -0.17272 0.18796)
						(xy -0.1651 0.19558) (xy -0.1651 0.7366) (xy -0.16256 0.76835) (xy -0.1524 0.8001) (xy -0.13716 0.82804)
						(xy -0.11684 0.85344) (xy -0.09144 0.87376) (xy -0.0635 0.889) (xy -0.03175 0.89916) (xy 0 0.9017)
						(xy 0.03175 0.89916) (xy 0.0635 0.889) (xy 0.09144 0.87376) (xy 0.11684 0.85344) (xy 0.13716 0.82804)
						(xy 0.1524 0.8001) (xy 0.16256 0.76835) (xy 0.1651 0.7366) (xy 0.1651 0.19685) (xy 0.17272 0.18923)
						(xy 0.17907 0.18034) (xy 0.18669 0.17145) (xy 0.19177 0.16256) (xy 0.19812 0.15367) (xy 0.20828 0.13335)
						(xy 0.21971 0.10287) (xy 0.22225 0.09271) (xy 0.22479 0.08128) (xy 0.22606 0.07112) (xy 0.2286 0.05969)
						(xy 0.2286 0.01651) (xy 0.22606 0.00508) (xy 0.22479 -0.00508) (xy 0.22225 -0.01651) (xy 0.21971 -0.02667)
						(xy 0.20828 -0.05715) (xy 0.19812 -0.07747) (xy 0.19177 -0.08636) (xy 0.18669 -0.09525) (xy 0.17907 -0.10414)
						(xy 0.17272 -0.11303) (xy 0.1651 -0.12065) (xy 0.1651 -0.7366) (xy 0.16256 -0.76835) (xy 0.1524 -0.8001)
						(xy 0.13716 -0.82804) (xy 0.11684 -0.85344) (xy 0.09144 -0.87376) (xy 0.0635 -0.889) (xy 0.03175 -0.89916)
					)
					(width 0)
					(fill yes)
				)
			)
		)
		(pad "9" smd custom
			(at -29.249878 -4.100068 180)
			(size 0.1143 0.1143)
			(layers "B.Cu" "B.Mask" "B.Paste")
			(net "GND")
			(options
				(clearance outline)
				(anchor circle)
			)
			(primitives
				(gr_poly
					(pts
						(xy 0 -0.9017) (xy -0.03175 -0.89916) (xy -0.0635 -0.889) (xy -0.09144 -0.87376) (xy -0.11684 -0.85344)
						(xy -0.13716 -0.82804) (xy -0.1524 -0.8001) (xy -0.16256 -0.76835) (xy -0.1651 -0.7366) (xy -0.1651 -0.44958)
						(xy -0.17272 -0.44196) (xy -0.19812 -0.4064) (xy -0.2032 -0.39624) (xy -0.20701 -0.38735) (xy -0.21209 -0.37719)
						(xy -0.2159 -0.36703) (xy -0.21844 -0.35687) (xy -0.22225 -0.34544) (xy -0.22352 -0.33528) (xy -0.22606 -0.32512)
						(xy -0.22733 -0.31369) (xy -0.22733 -0.30353) (xy -0.2286 -0.2921) (xy -0.22733 -0.28067) (xy -0.22733 -0.27051)
						(xy -0.22606 -0.25908) (xy -0.22352 -0.24892) (xy -0.22225 -0.23876) (xy -0.21844 -0.22733) (xy -0.2159 -0.21717)
						(xy -0.21209 -0.20701) (xy -0.20701 -0.19685) (xy -0.2032 -0.18796) (xy -0.19812 -0.1778) (xy -0.17272 -0.14224)
						(xy -0.1651 -0.13462) (xy -0.1651 0.7366) (xy -0.16256 0.76835) (xy -0.1524 0.8001) (xy -0.13716 0.82804)
						(xy -0.11684 0.85344) (xy -0.09144 0.87376) (xy -0.0635 0.889) (xy -0.03175 0.89916) (xy 0 0.9017)
						(xy 0.03175 0.89916) (xy 0.0635 0.889) (xy 0.09144 0.87376) (xy 0.11684 0.85344) (xy 0.13716 0.82804)
						(xy 0.1524 0.8001) (xy 0.16256 0.76835) (xy 0.1651 0.7366) (xy 0.1651 -0.13462) (xy 0.17272 -0.14224)
						(xy 0.19812 -0.1778) (xy 0.2032 -0.18796) (xy 0.20701 -0.19685) (xy 0.21209 -0.20701) (xy 0.2159 -0.21717)
						(xy 0.21844 -0.22733) (xy 0.22225 -0.23876) (xy 0.22352 -0.24892) (xy 0.22606 -0.25908) (xy 0.22733 -0.27051)
						(xy 0.22733 -0.28067) (xy 0.2286 -0.2921) (xy 0.22733 -0.30353) (xy 0.22733 -0.31369) (xy 0.22606 -0.32512)
						(xy 0.22352 -0.33528) (xy 0.22225 -0.34544) (xy 0.21844 -0.35687) (xy 0.2159 -0.36703) (xy 0.21209 -0.37719)
						(xy 0.20701 -0.38735) (xy 0.2032 -0.39624) (xy 0.19812 -0.4064) (xy 0.17272 -0.44196) (xy 0.1651 -0.44958)
						(xy 0.1651 -0.7366) (xy 0.16256 -0.76835) (xy 0.1524 -0.8001) (xy 0.13716 -0.82804) (xy 0.11684 -0.85344)
						(xy 0.09144 -0.87376) (xy 0.0635 -0.889) (xy 0.03175 -0.89916)
					)
					(width 0)
					(fill yes)
				)
			)
		)
		(pad "10" smd custom
			(at -28.949904 4.100068 180)
			(size 0.1143 0.1143)
			(layers "B.Cu" "B.Mask" "B.Paste")
			(net "M_B_DQS_DN0")
			(options
				(clearance outline)
				(anchor circle)
			)
			(primitives
				(gr_poly
					(pts
						(xy 0 -0.9017) (xy -0.03175 -0.89916) (xy -0.0635 -0.889) (xy -0.09144 -0.87376) (xy -0.11684 -0.85344)
						(xy -0.13716 -0.82804) (xy -0.1524 -0.8001) (xy -0.16256 -0.76835) (xy -0.1651 -0.7366) (xy -0.1651 0.13462)
						(xy -0.17272 0.14224) (xy -0.19812 0.1778) (xy -0.2032 0.18796) (xy -0.20701 0.19685) (xy -0.21209 0.20701)
						(xy -0.2159 0.21717) (xy -0.21844 0.22733) (xy -0.22225 0.23876) (xy -0.22352 0.24892) (xy -0.22606 0.25908)
						(xy -0.22733 0.27051) (xy -0.22733 0.28067) (xy -0.2286 0.2921) (xy -0.22733 0.30353) (xy -0.22733 0.31369)
						(xy -0.22606 0.32512) (xy -0.22352 0.33528) (xy -0.22225 0.34544) (xy -0.21844 0.35687) (xy -0.2159 0.36703)
						(xy -0.21209 0.37719) (xy -0.20701 0.38735) (xy -0.2032 0.39624) (xy -0.19812 0.4064) (xy -0.17272 0.44196)
						(xy -0.1651 0.44958) (xy -0.1651 0.7366) (xy -0.16256 0.76835) (xy -0.1524 0.8001) (xy -0.13716 0.82804)
						(xy -0.11684 0.85344) (xy -0.09144 0.87376) (xy -0.0635 0.889) (xy -0.03175 0.89916) (xy 0 0.9017)
						(xy 0.03175 0.89916) (xy 0.0635 0.889) (xy 0.09144 0.87376) (xy 0.11684 0.85344) (xy 0.13716 0.82804)
						(xy 0.1524 0.8001) (xy 0.16256 0.76835) (xy 0.1651 0.7366) (xy 0.1651 0.44958) (xy 0.17272 0.44196)
						(xy 0.19812 0.4064) (xy 0.2032 0.39624) (xy 0.20701 0.38735) (xy 0.21209 0.37719) (xy 0.2159 0.36703)
						(xy 0.21844 0.35687) (xy 0.22225 0.34544) (xy 0.22352 0.33528) (xy 0.22606 0.32512) (xy 0.22733 0.31369)
						(xy 0.22733 0.30353) (xy 0.2286 0.2921) (xy 0.22733 0.28067) (xy 0.22733 0.27051) (xy 0.22606 0.25908)
						(xy 0.22352 0.24892) (xy 0.22225 0.23876) (xy 0.21844 0.22733) (xy 0.2159 0.21717) (xy 0.21209 0.20701)
						(xy 0.20701 0.19685) (xy 0.2032 0.18796) (xy 0.19812 0.1778) (xy 0.17272 0.14224) (xy 0.1651 0.13462)
						(xy 0.1651 -0.7366) (xy 0.16256 -0.76835) (xy 0.1524 -0.8001) (xy 0.13716 -0.82804) (xy 0.11684 -0.85344)
						(xy 0.09144 -0.87376) (xy 0.0635 -0.889) (xy 0.03175 -0.89916)
					)
					(width 0)
					(fill yes)
				)
			)
		)
		(pad "11" smd custom
			(at -28.64993 -4.100068 180)
			(size 0.1143 0.1143)
			(layers "B.Cu" "B.Mask" "B.Paste")
			(net "GND")
			(options
				(clearance outline)
				(anchor circle)
			)
			(primitives
				(gr_poly
					(pts
						(xy 0 -0.9017) (xy -0.03175 -0.89916) (xy -0.0635 -0.889) (xy -0.09144 -0.87376) (xy -0.11684 -0.85344)
						(xy -0.13716 -0.82804) (xy -0.1524 -0.8001) (xy -0.16256 -0.76835) (xy -0.1651 -0.7366) (xy -0.1651 -0.19685)
						(xy -0.17272 -0.18923) (xy -0.17907 -0.18034) (xy -0.18669 -0.17145) (xy -0.19177 -0.16256) (xy -0.19812 -0.15367)
						(xy -0.20828 -0.13335) (xy -0.21971 -0.10287) (xy -0.22225 -0.09271) (xy -0.22479 -0.08128) (xy -0.22606 -0.07112)
						(xy -0.2286 -0.05969) (xy -0.2286 -0.01651) (xy -0.22606 -0.00508) (xy -0.22479 0.00508) (xy -0.22225 0.01651)
						(xy -0.21971 0.02667) (xy -0.20828 0.05715) (xy -0.19812 0.07747) (xy -0.19177 0.08636) (xy -0.18669 0.09525)
						(xy -0.17907 0.10414) (xy -0.17272 0.11303) (xy -0.1651 0.12065) (xy -0.1651 0.7366) (xy -0.16256 0.76835)
						(xy -0.1524 0.8001) (xy -0.13716 0.82804) (xy -0.11684 0.85344) (xy -0.09144 0.87376) (xy -0.0635 0.889)
						(xy -0.03175 0.89916) (xy 0 0.9017) (xy 0.03175 0.89916) (xy 0.0635 0.889) (xy 0.09144 0.87376)
						(xy 0.11684 0.85344) (xy 0.13716 0.82804) (xy 0.1524 0.8001) (xy 0.16256 0.76835) (xy 0.1651 0.7366)
						(xy 0.1651 0.11938) (xy 0.17272 0.11176) (xy 0.19812 0.0762) (xy 0.2032 0.06604) (xy 0.20701 0.05715)
						(xy 0.21209 0.04699) (xy 0.2159 0.03683) (xy 0.21844 0.02667) (xy 0.22225 0.01524) (xy 0.22352 0.00508)
						(xy 0.22606 -0.00508) (xy 0.22733 -0.01651) (xy 0.22733 -0.02667) (xy 0.2286 -0.0381) (xy 0.22733 -0.04953)
						(xy 0.22733 -0.05969) (xy 0.22606 -0.07112) (xy 0.22352 -0.08128) (xy 0.22225 -0.09144) (xy 0.21844 -0.10287)
						(xy 0.2159 -0.11303) (xy 0.21209 -0.12319) (xy 0.20701 -0.13335) (xy 0.2032 -0.14224) (xy 0.19812 -0.1524)
						(xy 0.17272 -0.18796) (xy 0.1651 -0.19558) (xy 0.1651 -0.7366) (xy 0.16256 -0.76835) (xy 0.1524 -0.8001)
						(xy 0.13716 -0.82804) (xy 0.11684 -0.85344) (xy 0.09144 -0.87376) (xy 0.0635 -0.889) (xy 0.03175 -0.89916)
					)
					(width 0)
					(fill yes)
				)
			)
		)
		(pad "12" smd custom
			(at -28.349956 4.100068 180)
			(size 0.1143 0.1143)
			(layers "B.Cu" "B.Mask" "B.Paste")
			(net "M_B_DQS_DP0")
			(options
				(clearance outline)
				(anchor circle)
			)
			(primitives
				(gr_poly
					(pts
						(xy 0 -0.9017) (xy -0.03175 -0.89916) (xy -0.0635 -0.889) (xy -0.09144 -0.87376) (xy -0.11684 -0.85344)
						(xy -0.13716 -0.82804) (xy -0.1524 -0.8001) (xy -0.16256 -0.76835) (xy -0.1651 -0.7366) (xy -0.1651 -0.11938)
						(xy -0.17272 -0.11176) (xy -0.19812 -0.0762) (xy -0.2032 -0.06604) (xy -0.20701 -0.05715) (xy -0.21209 -0.04699)
						(xy -0.2159 -0.03683) (xy -0.21844 -0.02667) (xy -0.22225 -0.01524) (xy -0.22352 -0.00508) (xy -0.22606 0.00508)
						(xy -0.22733 0.01651) (xy -0.22733 0.02667) (xy -0.2286 0.0381) (xy -0.22733 0.04953) (xy -0.22733 0.05969)
						(xy -0.22606 0.07112) (xy -0.22352 0.08128) (xy -0.22225 0.09144) (xy -0.21844 0.10287) (xy -0.2159 0.11303)
						(xy -0.21209 0.12319) (xy -0.20701 0.13335) (xy -0.2032 0.14224) (xy -0.19812 0.1524) (xy -0.17272 0.18796)
						(xy -0.1651 0.19558) (xy -0.1651 0.7366) (xy -0.16256 0.76835) (xy -0.1524 0.8001) (xy -0.13716 0.82804)
						(xy -0.11684 0.85344) (xy -0.09144 0.87376) (xy -0.0635 0.889) (xy -0.03175 0.89916) (xy 0 0.9017)
						(xy 0.03175 0.89916) (xy 0.0635 0.889) (xy 0.09144 0.87376) (xy 0.11684 0.85344) (xy 0.13716 0.82804)
						(xy 0.1524 0.8001) (xy 0.16256 0.76835) (xy 0.1651 0.7366) (xy 0.1651 0.19685) (xy 0.17272 0.18923)
						(xy 0.17907 0.18034) (xy 0.18669 0.17145) (xy 0.19177 0.16256) (xy 0.19812 0.15367) (xy 0.20828 0.13335)
						(xy 0.21971 0.10287) (xy 0.22225 0.09271) (xy 0.22479 0.08128) (xy 0.22606 0.07112) (xy 0.2286 0.05969)
						(xy 0.2286 0.01651) (xy 0.22606 0.00508) (xy 0.22479 -0.00508) (xy 0.22225 -0.01651) (xy 0.21971 -0.02667)
						(xy 0.20828 -0.05715) (xy 0.19812 -0.07747) (xy 0.19177 -0.08636) (xy 0.18669 -0.09525) (xy 0.17907 -0.10414)
						(xy 0.17272 -0.11303) (xy 0.1651 -0.12065) (xy 0.1651 -0.7366) (xy 0.16256 -0.76835) (xy 0.1524 -0.8001)
						(xy 0.13716 -0.82804) (xy 0.11684 -0.85344) (xy 0.09144 -0.87376) (xy 0.0635 -0.889) (xy 0.03175 -0.89916)
					)
					(width 0)
					(fill yes)
				)
			)
		)
		(pad "13" smd custom
			(at -28.049982 -4.100068 180)
			(size 0.1143 0.1143)
			(layers "B.Cu" "B.Mask" "B.Paste")
			(net "M_B_DQ2")
			(options
				(clearance outline)
				(anchor circle)
			)
			(primitives
				(gr_poly
					(pts
						(xy 0 -0.9017) (xy -0.03175 -0.89916) (xy -0.0635 -0.889) (xy -0.09144 -0.87376) (xy -0.11684 -0.85344)
						(xy -0.13716 -0.82804) (xy -0.1524 -0.8001) (xy -0.16256 -0.76835) (xy -0.1651 -0.7366) (xy -0.1651 -0.44958)
						(xy -0.17272 -0.44196) (xy -0.19812 -0.4064) (xy -0.2032 -0.39624) (xy -0.20701 -0.38735) (xy -0.21209 -0.37719)
						(xy -0.2159 -0.36703) (xy -0.21844 -0.35687) (xy -0.22225 -0.34544) (xy -0.22352 -0.33528) (xy -0.22606 -0.32512)
						(xy -0.22733 -0.31369) (xy -0.22733 -0.30353) (xy -0.2286 -0.2921) (xy -0.22733 -0.28067) (xy -0.22733 -0.27051)
						(xy -0.22606 -0.25908) (xy -0.22352 -0.24892) (xy -0.22225 -0.23876) (xy -0.21844 -0.22733) (xy -0.2159 -0.21717)
						(xy -0.21209 -0.20701) (xy -0.20701 -0.19685) (xy -0.2032 -0.18796) (xy -0.19812 -0.1778) (xy -0.17272 -0.14224)
						(xy -0.1651 -0.13462) (xy -0.1651 0.7366) (xy -0.16256 0.76835) (xy -0.1524 0.8001) (xy -0.13716 0.82804)
						(xy -0.11684 0.85344) (xy -0.09144 0.87376) (xy -0.0635 0.889) (xy -0.03175 0.89916) (xy 0 0.9017)
						(xy 0.03175 0.89916) (xy 0.0635 0.889) (xy 0.09144 0.87376) (xy 0.11684 0.85344) (xy 0.13716 0.82804)
						(xy 0.1524 0.8001) (xy 0.16256 0.76835) (xy 0.1651 0.7366) (xy 0.1651 -0.13462) (xy 0.17272 -0.14224)
						(xy 0.19812 -0.1778) (xy 0.2032 -0.18796) (xy 0.20701 -0.19685) (xy 0.21209 -0.20701) (xy 0.2159 -0.21717)
						(xy 0.21844 -0.22733) (xy 0.22225 -0.23876) (xy 0.22352 -0.24892) (xy 0.22606 -0.25908) (xy 0.22733 -0.27051)
						(xy 0.22733 -0.28067) (xy 0.2286 -0.2921) (xy 0.22733 -0.30353) (xy 0.22733 -0.31369) (xy 0.22606 -0.32512)
						(xy 0.22352 -0.33528) (xy 0.22225 -0.34544) (xy 0.21844 -0.35687) (xy 0.2159 -0.36703) (xy 0.21209 -0.37719)
						(xy 0.20701 -0.38735) (xy 0.2032 -0.39624) (xy 0.19812 -0.4064) (xy 0.17272 -0.44196) (xy 0.1651 -0.44958)
						(xy 0.1651 -0.7366) (xy 0.16256 -0.76835) (xy 0.1524 -0.8001) (xy 0.13716 -0.82804) (xy 0.11684 -0.85344)
						(xy 0.09144 -0.87376) (xy 0.0635 -0.889) (xy 0.03175 -0.89916)
					)
					(width 0)
					(fill yes)
				)
			)
		)
	)
)
